# SCM (Grand Teton) — schematic netlist excerpt (pin names and nets, part order shuffled) for the footprints in the layout excerpt that follows; sources: Cadence DE-HDL packaged netlist, KiCad conversion of 12092022_DA0F0TMDCD0_F0T_Management_Board_D_brd_V3_OCP.brd

R827  Q_RES  33.2 1% CHIP  pkg 0402LF  page 25 : A = RST_SPI_FLASH_BUF_R3_N ; B = RST_SPI_FLASH_BUF_N

PU42  NB695GDZ  NB695GD-Z IC  pkg QFN13_2X3  page 56
  VIN  = SW_P1V0_AUX_FLT
  PGND  = GND
  C1  = P1V0_AUX_VCC
  C0  = GND
  EN  = EN_P1V0_AUX_R
  \lp#\  = P1V0_AUX_VCC
  MODE  = P1V0_AUX_MODE
  SW  = SW_P1V0_AUX_SW
  BST  = SW_P1V0_AUX_BST
  \3v3\  = P1V0_AUX_VCC
  AGND  = GND
  VOUT  = P1V0_AUX
  PG  = PWRGD_P1V0_AUX_R

(kicad_pcb
	(version 20260206)
	(generator "pcbnew")
	(generator_version "10.0")
	(general
		(thickness 1.6)
		(legacy_teardrops no)
	)
	(paper "A4")
	(title_block
		(title "12092022_DA0F0TMDCD0_F0T_Management_Board_D_brd_V3_OCP.brd")
		(comment 1 "Grand Teton / footprints 116-117 of 1440")
	)
	(layers
		(0 "F.Cu" signal "TOP")
		(4 "In1.Cu" signal "GND")
		(6 "In2.Cu" signal "IN1")
		(8 "In3.Cu" signal "GND1")
		(10 "In4.Cu" signal "IN2")
		(12 "In5.Cu" signal "VCC")
		(14 "In6.Cu" signal "VCC1")
		(16 "In7.Cu" signal "IN3")
		(18 "In8.Cu" signal "GND2")
		(20 "In9.Cu" signal "IN4")
		(22 "In10.Cu" signal "GND3")
		(2 "B.Cu" signal "BOTTOM")
		(9 "F.Adhes" user "F.Adhesive")
		(11 "B.Adhes" user "B.Adhesive")
		(13 "F.Paste" user "Package Geometry/Pastemask Top")
		(15 "B.Paste" user "Package Geometry/Pastemask Bottom")
		(5 "F.SilkS" user "Ref Des/Silkscreen Top")
		(7 "B.SilkS" user "Ref Des/Silkscreen Bottom")
		(1 "F.Mask" user "Board Geometry/Soldermask Top")
		(3 "B.Mask" user "Board Geometry/Soldermask Bottom")
		(17 "Dwgs.User" user "User.Drawings")
		(19 "Cmts.User" user "User.Comments")
		(21 "Eco1.User" user "User.Eco1")
		(23 "Eco2.User" user "User.Eco2")
		(25 "Edge.Cuts" user "Board Geometry/Outline")
		(27 "Margin" user)
		(31 "F.CrtYd" user "Package Geometry/Place Bound Top")
		(29 "B.CrtYd" user "Package Geometry/Place Bound Bottom")
		(35 "F.Fab" user "Ref Des/Assembly Top")
		(33 "B.Fab" user "Ref Des/Assembly Bottom")
	)
	(footprint ""
		(layer "F.Cu")
		(at 19.320002 -32.312356 -90)
		(property "Reference" "PU42"
			(at -0.174244 -3.007868 90)
			(unlocked yes)
			(layer "F.SilkS")
			(effects
				(font
					(size 0.7874 0.5842)
					(thickness 0.1524)
				)
				(justify left)
			)
		)
		(property "Value" ""
			(at 0 0 270)
			(layer "F.Fab")
			(effects
				(font
					(size 1.27 1.27)
				)
			)
		)
		(duplicate_pad_numbers_are_jumpers no)
		(fp_line
			(start -1.050036 1.549908)
			(end -1.016 1.549908)
			(stroke
				(width 0.1524)
				(type default)
			)
			(layer "F.SilkS")
		)
		(fp_line
			(start 1.016 1.549908)
			(end 1.050036 1.549908)
			(stroke
				(width 0.1524)
				(type default)
			)
			(layer "F.SilkS")
		)
		(fp_line
			(start 1.050036 1.549908)
			(end 1.050036 0.762)
			(stroke
				(width 0.1524)
				(type default)
			)
			(layer "F.SilkS")
		)
		(fp_line
			(start -1.050036 0.762)
			(end -1.050036 1.549908)
			(stroke
				(width 0.1524)
				(type default)
			)
			(layer "F.SilkS")
		)
		(fp_line
			(start -1.050036 -0.2286)
			(end -1.050036 0.2286)
			(stroke
				(width 0.1524)
				(type default)
			)
			(layer "F.SilkS")
		)
		(fp_line
			(start 1.050036 -0.762)
			(end 1.050036 -1.549908)
			(stroke
				(width 0.1524)
				(type default)
			)
			(layer "F.SilkS")
		)
		(fp_line
			(start -1.050036 -1.549908)
			(end -1.050036 -0.762)
			(stroke
				(width 0.1524)
				(type default)
			)
			(layer "F.SilkS")
		)
		(fp_line
			(start -1.016 -1.549908)
			(end -1.050036 -1.549908)
			(stroke
				(width 0.1524)
				(type default)
			)
			(layer "F.SilkS")
		)
		(fp_line
			(start 1.050036 -1.549908)
			(end 1.016 -1.549908)
			(stroke
				(width 0.1524)
				(type default)
			)
			(layer "F.SilkS")
		)
		(fp_poly
			(pts
				(xy -1.52908 -1.280668) (xy -1.373124 -0.813054) (xy -1.840484 -0.96901)
			)
			(stroke
				(width 0)
				(type default)
			)
			(fill yes)
			(layer "F.SilkS")
		)
		(fp_line
			(start -1.050036 1.549908)
			(end 1.050036 1.549908)
			(stroke
				(width 0.1)
				(type default)
			)
			(layer "F.Fab")
		)
		(fp_line
			(start 1.050036 1.549908)
			(end 1.050036 -1.549908)
			(stroke
				(width 0.1)
				(type default)
			)
			(layer "F.Fab")
		)
		(fp_line
			(start -1.050036 -1.549908)
			(end -1.050036 1.549908)
			(stroke
				(width 0.1)
				(type default)
			)
			(layer "F.Fab")
		)
		(fp_line
			(start 1.050036 -1.549908)
			(end -1.050036 -1.549908)
			(stroke
				(width 0.1)
				(type default)
			)
			(layer "F.Fab")
		)
		(fp_poly
			(pts
				(xy -1.851914 -0.720344) (xy -1.411224 -0.499872) (xy -1.851914 -0.279654)
			)
			(stroke
				(width 0)
				(type default)
			)
			(fill yes)
			(layer "F.Fab")
		)
		(pad "1" smd rect
			(at -0.54991 -0.499872)
			(size 0.254 1.4986)
			(layers "F.Cu" "F.Mask" "F.Paste")
			(net "SW_P1V0_AUX_FLT")
		)
		(pad "2" smd rect
			(at -0.54991 0.499872)
			(size 0.254 1.4986)
			(layers "F.Cu" "F.Mask" "F.Paste")
			(net "GND")
		)
		(pad "3" smd rect
			(at -0.750062 1.450086 270)
			(size 0.254 0.7112)
			(layers "F.Cu" "F.Mask" "F.Paste")
			(net "P1V0_AUX_VCC")
		)
		(pad "4" smd rect
			(at -0.249936 1.450086 270)
			(size 0.254 0.7112)
			(layers "F.Cu" "F.Mask" "F.Paste")
			(net "GND")
		)
		(pad "5" smd rect
			(at 0.249936 1.450086 270)
			(size 0.254 0.7112)
			(layers "F.Cu" "F.Mask" "F.Paste")
			(net "EN_P1V0_AUX_R")
		)
		(pad "6" smd rect
			(at 0.750062 1.450086 270)
			(size 0.254 0.7112)
			(layers "F.Cu" "F.Mask" "F.Paste")
			(net "P1V0_AUX_VCC")
		)
		(pad "7" smd rect
			(at 0.94996 0.499872)
			(size 0.254 0.7112)
			(layers "F.Cu" "F.Mask" "F.Paste")
			(net "P1V0_AUX_MODE")
		)
		(pad "8" smd rect
			(at 0.54991 0)
			(size 0.254 1.4986)
			(layers "F.Cu" "F.Mask" "F.Paste")
			(net "SW_P1V0_AUX_SW")
		)
		(pad "9" smd rect
			(at 0.94996 -0.499872)
			(size 0.254 0.7112)
			(layers "F.Cu" "F.Mask" "F.Paste")
			(net "SW_P1V0_AUX_BST")
		)
		(pad "10" smd rect
			(at 0.750062 -1.450086 270)
			(size 0.254 0.7112)
			(layers "F.Cu" "F.Mask" "F.Paste")
			(net "P1V0_AUX_VCC")
		)
		(pad "11" smd rect
			(at 0.249936 -1.450086 270)
			(size 0.254 0.7112)
			(layers "F.Cu" "F.Mask" "F.Paste")
			(net "GND")
		)
		(pad "12" smd rect
			(at -0.249936 -1.450086 270)
			(size 0.254 0.7112)
			(layers "F.Cu" "F.Mask" "F.Paste")
			(net "P1V0_AUX")
		)
		(pad "13" smd rect
			(at -0.750062 -1.450086 270)
			(size 0.254 0.7112)
			(layers "F.Cu" "F.Mask" "F.Paste")
			(net "PWRGD_P1V0_AUX_R")
		)
	)
	(footprint ""
		(layer "F.Cu")
		(at 17.5768 -46.3042 90)
		(property "Reference" "R827"
			(at 0 0 90)
			(layer "F.SilkS")
			(hide yes)
			(effects
				(font
					(size 1.27 1.27)
				)
			)
		)
		(property "Value" ""
			(at 0 0 90)
			(layer "F.Fab")
			(effects
				(font
					(size 1.27 1.27)
				)
			)
		)
		(duplicate_pad_numbers_are_jumpers no)
		(fp_line
			(start 0.7874 -0.4064)
			(end 0.7874 0.4064)
			(stroke
				(width 0.1524)
				(type default)
			)
			(layer "F.SilkS")
		)
		(fp_line
			(start -0.7874 -0.4064)
			(end 0.7874 -0.4064)
			(stroke
				(width 0.1524)
				(type default)
			)
			(layer "F.SilkS")
		)
		(fp_line
			(start 0.7874 0.4064)
			(end -0.7874 0.4064)
			(stroke
				(width 0.1524)
				(type default)
			)
			(layer "F.SilkS")
		)
		(fp_line
			(start -0.7874 0.4064)
			(end -0.7874 -0.4064)
			(stroke
				(width 0.1524)
				(type default)
			)
			(layer "F.SilkS")
		)
		(fp_line
			(start -0.12065 -0.305054)
			(end -0.12065 -0.2794)
			(stroke
				(width 0.1)
				(type default)
			)
			(layer "F.Fab")
		)
		(fp_line
			(start -0.67945 -0.305054)
			(end -0.12065 -0.305054)
			(stroke
				(width 0.1)
				(type default)
			)
			(layer "F.Fab")
		)
		(fp_line
			(start 0.67945 -0.3048)
			(end 0.67945 0.3048)
			(stroke
				(width 0.1)
				(type default)
			)
			(layer "F.Fab")
		)
		(fp_line
			(start 0.12065 -0.3048)
			(end 0.67945 -0.3048)
			(stroke
				(width 0.1)
				(type default)
			)
			(layer "F.Fab")
		)
		(fp_line
			(start 0.12065 -0.2794)
			(end 0.12065 -0.3048)
			(stroke
				(width 0.1)
				(type default)
			)
			(layer "F.Fab")
		)
		(fp_line
			(start -0.12065 -0.2794)
			(end 0.12065 -0.2794)
			(stroke
				(width 0.1)
				(type default)
			)
			(layer "F.Fab")
		)
		(fp_line
			(start 0.120396 0.2794)
			(end -0.12065 0.2794)
			(stroke
				(width 0.1)
				(type default)
			)
			(layer "F.Fab")
		)
		(fp_line
			(start -0.12065 0.2794)
			(end -0.12065 0.3048)
			(stroke
				(width 0.1)
				(type default)
			)
			(layer "F.Fab")
		)
		(fp_line
			(start 0.67945 0.3048)
			(end 0.120396 0.3048)
			(stroke
				(width 0.1)
				(type default)
			)
			(layer "F.Fab")
		)
		(fp_line
			(start 0.120396 0.3048)
			(end 0.120396 0.2794)
			(stroke
				(width 0.1)
				(type default)
			)
			(layer "F.Fab")
		)
		(fp_line
			(start -0.12065 0.3048)
			(end -0.67945 0.3048)
			(stroke
				(width 0.1)
				(type default)
			)
			(layer "F.Fab")
		)
		(fp_line
			(start -0.67945 0.3048)
			(end -0.67945 -0.305054)
			(stroke
				(width 0.1)
				(type default)
			)
			(layer "F.Fab")
		)
		(pad "1" smd circle
			(at -0.40005 0 90)
			(size 0 0)
			(layers "F.Cu" "F.Mask" "F.Paste")
			(net "RST_SPI_FLASH_BUF_R3_N")
		)
		(pad "2" smd circle
			(at 0.40005 0 90)
			(size 0 0)
			(layers "F.Cu" "F.Mask" "F.Paste")
			(net "RST_SPI_FLASH_BUF_N")
		)
	)
)
